# BASEBOARD_FAB2 (Tioga Pass) — schematic netlist excerpt (pin names and nets, part order shuffled) for the footprints in the layout excerpt that follows; sources: Cadence DE-HDL packaged netlist, KiCad conversion of Wiwynn_Tioga_Pass_MB.brd

C3M28  CAP  0.22UF 16V 10% X7R  pkg 0402  page 105 : A = P3E_CPU0_PE1_PCH_R_RXP<10> ; B = P3E_CPU0_PE1_PCH_RXP<10>
R7P25  RES  49.9 1% CHIP  pkg 0402  page 55 : A = H_PM_SYNC_GTL_R2 ; B = H_PM_SYNC_GTL
C3N32  CAP_A  1.0UF 6.3V 10% X6S  pkg 0402V  page 137 : A = RST_SRTCRST_N ; B = GND

(kicad_pcb
	(version 20260206)
	(generator "pcbnew")
	(generator_version "10.0")
	(general
		(thickness 1.6)
		(legacy_teardrops no)
	)
	(paper "A4")
	(title_block
		(title "Wiwynn_Tioga_Pass_MB.brd")
		(comment 1 "Tioga Pass / footprints 2576-2578 of 4770")
	)
	(layers
		(0 "F.Cu" signal "TOP")
		(4 "In1.Cu" signal "L2GND")
		(6 "In2.Cu" signal "L3")
		(8 "In3.Cu" signal "L4GND")
		(10 "In4.Cu" signal "L5")
		(12 "In5.Cu" signal "L6GND")
		(14 "In6.Cu" signal "L7VCC")
		(16 "In7.Cu" signal "L8VCC")
		(18 "In8.Cu" signal "L9GND")
		(20 "In9.Cu" signal "L10")
		(22 "In10.Cu" signal "L11GND")
		(24 "In11.Cu" signal "L12")
		(26 "In12.Cu" signal "L13GND")
		(2 "B.Cu" signal "BOTTOM")
		(9 "F.Adhes" user "F.Adhesive")
		(11 "B.Adhes" user "B.Adhesive")
		(13 "F.Paste" user "Package Geometry/Pastemask Top")
		(15 "B.Paste" user "Package Geometry/Pastemask Bottom")
		(5 "F.SilkS" user "Ref Des/Silkscreen Top")
		(7 "B.SilkS" user "Ref Des/Silkscreen Bottom")
		(1 "F.Mask" user "Board Geometry/Soldermask Top")
		(3 "B.Mask" user "Board Geometry/Soldermask Bottom")
		(17 "Dwgs.User" user "User.Drawings")
		(19 "Cmts.User" user "User.Comments")
		(21 "Eco1.User" user "User.Eco1")
		(23 "Eco2.User" user "User.Eco2")
		(25 "Edge.Cuts" user "Board Geometry/Outline")
		(27 "Margin" user)
		(31 "F.CrtYd" user "Package Geometry/Place Bound Top")
		(29 "B.CrtYd" user "Package Geometry/Place Bound Bottom")
		(35 "F.Fab" user "Ref Des/Assembly Top")
		(33 "B.Fab" user "Ref Des/Assembly Bottom")
	)
	(footprint ""
		(layer "B.Cu")
		(at 130.61188 -67.764914)
		(property "Reference" "R7P25"
			(at 0 0 0)
			(layer "B.SilkS")
			(hide yes)
			(effects
				(font
					(size 1.27 1.27)
				)
				(justify mirror)
			)
		)
		(property "Value" ""
			(at 0 0 0)
			(layer "B.Fab")
			(effects
				(font
					(size 1.27 1.27)
				)
				(justify mirror)
			)
		)
		(duplicate_pad_numbers_are_jumpers no)
		(fp_poly
			(pts
				(xy 0.2794 -0.1016) (xy -0.2794 -0.1016) (xy -0.2794 0.9906) (xy 0.2794 0.9906)
			)
			(stroke
				(width 0)
				(type default)
			)
			(fill no)
			(layer "B.CrtYd")
		)
		(fp_line
			(start -0.2794 -0.1016)
			(end 0.2794 -0.1016)
			(stroke
				(width 0.1)
				(type default)
			)
			(layer "B.Fab")
		)
		(fp_line
			(start -0.2794 0.9906)
			(end -0.2794 -0.1016)
			(stroke
				(width 0.1)
				(type default)
			)
			(layer "B.Fab")
		)
		(fp_line
			(start 0.2794 -0.1016)
			(end 0.2794 0.9906)
			(stroke
				(width 0.1)
				(type default)
			)
			(layer "B.Fab")
		)
		(fp_line
			(start 0.2794 0.9906)
			(end -0.2794 0.9906)
			(stroke
				(width 0.1)
				(type default)
			)
			(layer "B.Fab")
		)
		(pad "1" smd rect
			(at 0 0 180)
			(size 0.508 0.508)
			(layers "B.Cu" "B.Mask" "B.Paste")
			(net "H_PM_SYNC_GTL_R2")
		)
		(pad "2" smd rect
			(at 0 0.889 180)
			(size 0.508 0.508)
			(layers "B.Cu" "B.Mask" "B.Paste")
			(net "H_PM_SYNC_GTL")
		)
		(zone
			(layer "B.Cu")
			(hatch none 0.5)
			(connect_pads
				(clearance 0)
			)
			(min_thickness 0.25)
			(keepout
				(tracks allowed)
				(vias not_allowed)
				(pads allowed)
				(copperpour not_allowed)
				(footprints allowed)
			)
			(placement
				(enabled no)
				(sheetname "")
			)
			(fill
				(thermal_gap 0.5)
				(thermal_bridge_width 0.5)
				(island_removal_mode 0)
			)
			(polygon
				(pts
					(xy 130.86588 -67.510914) (xy 130.35788 -67.510914) (xy 130.35788 -67.129914) (xy 130.86588 -67.129914)
				)
			)
		)
		(zone
			(layer "B.Cu")
			(hatch none 0.5)
			(connect_pads
				(clearance 0)
			)
			(min_thickness 0.25)
			(keepout
				(tracks not_allowed)
				(vias allowed)
				(pads allowed)
				(copperpour not_allowed)
				(footprints allowed)
			)
			(placement
				(enabled no)
				(sheetname "")
			)
			(fill
				(thermal_gap 0.5)
				(thermal_bridge_width 0.5)
				(island_removal_mode 0)
			)
			(polygon
				(pts
					(xy 130.86588 -67.129914) (xy 130.35788 -67.129914) (xy 130.35788 -67.510914) (xy 130.86588 -67.510914)
				)
			)
		)
	)
	(footprint ""
		(layer "B.Cu")
		(at 375.666 -101.1936 -90)
		(property "Reference" "C3N32"
			(at 0 0 90)
			(layer "B.SilkS")
			(hide yes)
			(effects
				(font
					(size 1.27 1.27)
				)
				(justify mirror)
			)
		)
		(property "Value" ""
			(at 0 0 90)
			(layer "B.Fab")
			(effects
				(font
					(size 1.27 1.27)
				)
				(justify mirror)
			)
		)
		(duplicate_pad_numbers_are_jumpers no)
		(fp_poly
			(pts
				(xy -0.3048 -0.1016) (xy -0.3048 0.9906) (xy 0.3048 0.9906) (xy 0.3048 -0.1016)
			)
			(stroke
				(width 0)
				(type default)
			)
			(fill no)
			(layer "B.CrtYd")
		)
		(fp_line
			(start -0.3048 0.9906)
			(end -0.3048 -0.1016)
			(stroke
				(width 0.1)
				(type default)
			)
			(layer "B.Fab")
		)
		(fp_line
			(start 0.3048 0.9906)
			(end -0.3048 0.9906)
			(stroke
				(width 0.1)
				(type default)
			)
			(layer "B.Fab")
		)
		(fp_line
			(start -0.3048 -0.1016)
			(end 0.3048 -0.1016)
			(stroke
				(width 0.1)
				(type default)
			)
			(layer "B.Fab")
		)
		(fp_line
			(start 0.3048 -0.1016)
			(end 0.3048 0.9906)
			(stroke
				(width 0.1)
				(type default)
			)
			(layer "B.Fab")
		)
		(pad "1" smd rect
			(at 0 0 90)
			(size 0.508 0.508)
			(layers "B.Cu" "B.Mask" "B.Paste")
			(net "RST_SRTCRST_N")
		)
		(pad "2" smd rect
			(at 0 0.889 90)
			(size 0.508 0.508)
			(layers "B.Cu" "B.Mask" "B.Paste")
			(net "GND")
		)
		(zone
			(layer "B.Cu")
			(hatch none 0.5)
			(connect_pads
				(clearance 0)
			)
			(min_thickness 0.25)
			(keepout
				(tracks not_allowed)
				(vias allowed)
				(pads allowed)
				(copperpour not_allowed)
				(footprints allowed)
			)
			(placement
				(enabled no)
				(sheetname "")
			)
			(fill
				(thermal_gap 0.5)
				(thermal_bridge_width 0.5)
				(island_removal_mode 0)
			)
			(polygon
				(pts
					(xy 375.031 -100.9396) (xy 375.031 -101.4476) (xy 375.412 -101.4476) (xy 375.412 -100.9396)
				)
			)
		)
		(zone
			(layer "B.Cu")
			(hatch none 0.5)
			(connect_pads
				(clearance 0)
			)
			(min_thickness 0.25)
			(keepout
				(tracks allowed)
				(vias not_allowed)
				(pads allowed)
				(copperpour not_allowed)
				(footprints allowed)
			)
			(placement
				(enabled no)
				(sheetname "")
			)
			(fill
				(thermal_gap 0.5)
				(thermal_bridge_width 0.5)
				(island_removal_mode 0)
			)
			(polygon
				(pts
					(xy 375.412 -100.9396) (xy 375.412 -101.4476) (xy 375.031 -101.4476) (xy 375.031 -100.9396)
				)
			)
		)
	)
	(footprint ""
		(layer "B.Cu")
		(at 362.671614 -125.558042 -90)
		(property "Reference" "C3M28"
			(at 0 0 90)
			(layer "B.SilkS")
			(hide yes)
			(effects
				(font
					(size 1.27 1.27)
				)
				(justify mirror)
			)
		)
		(property "Value" ""
			(at 0 0 90)
			(layer "B.Fab")
			(effects
				(font
					(size 1.27 1.27)
				)
				(justify mirror)
			)
		)
		(duplicate_pad_numbers_are_jumpers no)
		(fp_poly
			(pts
				(xy -0.3048 -0.1016) (xy -0.3048 0.9906) (xy 0.3048 0.9906) (xy 0.3048 -0.1016)
			)
			(stroke
				(width 0)
				(type default)
			)
			(fill no)
			(layer "B.CrtYd")
		)
		(fp_line
			(start -0.3048 0.9906)
			(end -0.3048 -0.1016)
			(stroke
				(width 0.1)
				(type default)
			)
			(layer "B.Fab")
		)
		(fp_line
			(start 0.3048 0.9906)
			(end -0.3048 0.9906)
			(stroke
				(width 0.1)
				(type default)
			)
			(layer "B.Fab")
		)
		(fp_line
			(start -0.3048 -0.1016)
			(end 0.3048 -0.1016)
			(stroke
				(width 0.1)
				(type default)
			)
			(layer "B.Fab")
		)
		(fp_line
			(start 0.3048 -0.1016)
			(end 0.3048 0.9906)
			(stroke
				(width 0.1)
				(type default)
			)
			(layer "B.Fab")
		)
		(pad "1" smd rect
			(at 0 0 90)
			(size 0.508 0.508)
			(layers "B.Cu" "B.Mask" "B.Paste")
			(net "P3E_CPU0_PE1_PCH_R_RXP<10>")
		)
		(pad "2" smd rect
			(at 0 0.889 90)
			(size 0.508 0.508)
			(layers "B.Cu" "B.Mask" "B.Paste")
			(net "P3E_CPU0_PE1_PCH_RXP<10>")
		)
		(zone
			(layer "B.Cu")
			(hatch none 0.5)
			(connect_pads
				(clearance 0)
			)
			(min_thickness 0.25)
			(keepout
				(tracks not_allowed)
				(vias allowed)
				(pads allowed)
				(copperpour not_allowed)
				(footprints allowed)
			)
			(placement
				(enabled no)
				(sheetname "")
			)
			(fill
				(thermal_gap 0.5)
				(thermal_bridge_width 0.5)
				(island_removal_mode 0)
			)
			(polygon
				(pts
					(xy 362.036614 -125.304042) (xy 362.036614 -125.812042) (xy 362.417614 -125.812042) (xy 362.417614 -125.304042)
				)
			)
		)
		(zone
			(layer "B.Cu")
			(hatch none 0.5)
			(connect_pads
				(clearance 0)
			)
			(min_thickness 0.25)
			(keepout
				(tracks allowed)
				(vias not_allowed)
				(pads allowed)
				(copperpour not_allowed)
				(footprints allowed)
			)
			(placement
				(enabled no)
				(sheetname "")
			)
			(fill
				(thermal_gap 0.5)
				(thermal_bridge_width 0.5)
				(island_removal_mode 0)
			)
			(polygon
				(pts
					(xy 362.417614 -125.304042) (xy 362.417614 -125.812042) (xy 362.036614 -125.812042) (xy 362.036614 -125.304042)
				)
			)
		)
	)
)
